#ISCELL
  logical_power design_note *
  *
#ISCELL
  mstr_misc dns *
  *
#ISCELL
  pure_quanta quanta_title_block_c *
  *
#ISCELL
  logical_power universal_gnd *
  page137_i101
#CELL
  pure_quanta q_res *
  page137_i102
#CELL
  pure_quanta q_res *
  page137_i103
#ISCELL
  logical_power universal_gnd *
  page137_i104
#CELL
  pure_quanta q_res *
  page137_i105
#CELL
  pure_quanta q_res *
  page137_i106
#ISCELL
  logical_power universal_gnd *
  page137_i107
#CELL
  pure_quanta nc7sb3157 *
  page137_i109
#CELL
  pure_quanta q_cap *
  page137_i110
#ISCELL
  logical_power universal_power *
  page137_i111
#CELL
  pure_quanta q_cap *
  page137_i112
#ISCELL
  logical_power universal_gnd *
  page137_i113
#ISCELL
  standard offpage *
  page137_i114
#ISCELL
  standard offpage *
  page137_i115
#CELL
  pure_quanta q_res *
  page137_i116
#ISCELL
  logical_power universal_gnd *
  page137_i117
#ISCELL
  logical_power universal_power *
  page137_i118
#ISCELL
  standard offpage *
  page137_i119
#CELL
  pure_quanta 74cbtlv3126pw *
  page137_i84
#ISCELL
  standard offpage *
  page137_i85
#ISCELL
  standard offpage *
  page137_i86
#CELL
  pure_quanta q_res *
  page137_i87
#CELL
  pure_quanta q_res *
  page137_i88
#ISCELL
  logical_power universal_power *
  page137_i89
#CELL
  pure_quanta q_cap *
  page137_i90
#ISCELL
  logical_power universal_gnd *
  page137_i91
#ISCELL
  logical_power universal_gnd *
  page137_i92
#ISCELL
  logical_power universal_power *
  page137_i93
#ISCELL
  logical_power universal_gnd *
  page137_i94
#CELL
  pure_quanta q_cap *
  page137_i95
#CELL
  pure_quanta mosfet_n *
  page137_i96
#CELL
  pure_quanta q_res *
  page137_i97
#CELL
  pure_quanta q_res *
  page137_i98
